(kicad_pcb
	(version 20260206)
	(generator "pcbnew")
	(generator_version "10.0")
	(general
		(thickness 1.6)
		(legacy_teardrops no)
	)
	(paper "A4")
	(title_block
		(title "timecard-production-celestica-r4006 — R4006-B0001-02_R01.brd")
		(comment 1 "Time Appliance Project (Time Card) / footprints 1059-1064 of 1113")
	)
	(layers
		(0 "F.Cu" signal "TOP")
		(4 "In1.Cu" signal "L02_GND1")
		(6 "In2.Cu" signal "L03_SIG1")
		(8 "In3.Cu" signal "L04_GND2")
		(10 "In4.Cu" signal "L05_VCC1")
		(12 "In5.Cu" signal "L06_VCC2")
		(14 "In6.Cu" signal "L07_GND3")
		(16 "In7.Cu" signal "L08_SIG2")
		(18 "In8.Cu" signal "L09_GND4")
		(2 "B.Cu" signal "BOTTOM")
		(9 "F.Adhes" user "F.Adhesive")
		(11 "B.Adhes" user "B.Adhesive")
		(13 "F.Paste" user "Package Geometry/Pastemask Top")
		(15 "B.Paste" user "Package Geometry/Pastemask Bottom")
		(5 "F.SilkS" user "Ref Des/Silkscreen Top")
		(7 "B.SilkS" user "Ref Des/Silkscreen Bottom")
		(1 "F.Mask" user "Board Geometry/Soldermask Top")
		(3 "B.Mask" user "Board Geometry/Soldermask Bottom")
		(17 "Dwgs.User" user "User.Drawings")
		(19 "Cmts.User" user "User.Comments")
		(21 "Eco1.User" user "User.Eco1")
		(23 "Eco2.User" user "User.Eco2")
		(25 "Edge.Cuts" user "Board Geometry/Outline")
		(27 "Margin" user)
		(31 "F.CrtYd" user "Package Geometry/Place Bound Top")
		(29 "B.CrtYd" user "Package Geometry/Place Bound Bottom")
		(35 "F.Fab" user "Ref Des/Assembly Top")
		(33 "B.Fab" user "Ref Des/Assembly Bottom")
	)
	(footprint ""
		(layer "B.Cu")
		(at 145.8214 -97.9678 180)
		(property "Reference" "R10"
			(at -3.1496 0.03683 0)
			(unlocked yes)
			(layer "B.SilkS")
			(effects
				(font
					(size 0.7874 0.5842)
					(thickness 0.1524)
				)
				(justify mirror)
			)
		)
		(property "Value" "VAL*"
			(at -0.02032 2.13233 180)
			(unlocked yes)
			(layer "B.Fab")
			(hide yes)
			(effects
				(font
					(size 0.7874 0.5842)
					(thickness 0.1524)
				)
				(justify mirror)
			)
		)
		(property "Device Type" "RESISTOR-G155-11002-01,10KOHM,A"
			(at -0.008382 1.210564 180)
			(unlocked yes)
			(layer "B.Fab")
			(hide yes)
			(effects
				(font
					(size 0.7874 0.5842)
					(thickness 0.1524)
				)
				(justify mirror)
			)
		)
		(property "User Part Number" "PARTNUM*"
			(at -0.02032 4.024884 180)
			(unlocked yes)
			(layer "Cmts.User")
			(hide yes)
			(effects
				(font
					(size 0.7874 0.5842)
					(thickness 0.1524)
				)
				(justify mirror)
			)
		)
		(property "Tolerance" "TOL*"
			(at -0.044704 3.05435 180)
			(unlocked yes)
			(layer "Cmts.User")
			(hide yes)
			(effects
				(font
					(size 0.7874 0.5842)
					(thickness 0.1524)
				)
				(justify mirror)
			)
		)
		(duplicate_pad_numbers_are_jumpers no)
		(fp_line
			(start 1.143 0.5588)
			(end -1.143 0.5588)
			(stroke
				(width 0.1)
				(type default)
			)
			(layer "B.SilkS")
		)
		(fp_line
			(start 1.143 -0.5588)
			(end 1.143 0.5588)
			(stroke
				(width 0.1)
				(type default)
			)
			(layer "B.SilkS")
		)
		(fp_line
			(start -1.143 0.5588)
			(end -1.143 -0.5588)
			(stroke
				(width 0.1)
				(type default)
			)
			(layer "B.SilkS")
		)
		(fp_line
			(start -1.143 -0.5588)
			(end 1.143 -0.5588)
			(stroke
				(width 0.1)
				(type default)
			)
			(layer "B.SilkS")
		)
		(fp_rect
			(start 1.143 -0.5588)
			(end -1.143 0.5588)
			(stroke
				(width 0)
				(type default)
			)
			(fill no)
			(layer "B.CrtYd")
		)
		(fp_line
			(start 0.508 0.3048)
			(end -0.508 0.3048)
			(stroke
				(width 0.1)
				(type default)
			)
			(layer "B.Fab")
		)
		(fp_line
			(start 0.508 -0.3048)
			(end 0.508 0.3048)
			(stroke
				(width 0.1)
				(type default)
			)
			(layer "B.Fab")
		)
		(fp_line
			(start -0.508 0.3048)
			(end -0.508 -0.3048)
			(stroke
				(width 0.1)
				(type default)
			)
			(layer "B.Fab")
		)
		(fp_line
			(start -0.508 -0.3048)
			(end 0.508 -0.3048)
			(stroke
				(width 0.1)
				(type default)
			)
			(layer "B.Fab")
		)
		(pad "1" smd rect
			(at 0.5334 0)
			(size 0.7112 0.6096)
			(layers "B.Cu" "B.Mask" "B.Paste")
			(net "XP12R0V_A_IMON")
		)
		(pad "2" smd rect
			(at -0.5334 0)
			(size 0.7112 0.6096)
			(layers "B.Cu" "B.Mask" "B.Paste")
			(net "SG")
		)
		(zone
			(layer "B.Cu")
			(hatch none 0.5)
			(connect_pads
				(clearance 0)
			)
			(min_thickness 0.25)
			(keepout
				(tracks allowed)
				(vias not_allowed)
				(pads allowed)
				(copperpour not_allowed)
				(footprints allowed)
			)
			(placement
				(enabled no)
				(sheetname "")
			)
			(fill
				(thermal_gap 0.5)
				(thermal_bridge_width 0.5)
				(island_removal_mode 0)
			)
			(polygon
				(pts
					(xy 145.7452 -97.663) (xy 145.8976 -97.663) (xy 145.8976 -98.2726) (xy 145.7452 -98.2726)
				)
			)
		)
	)
	(footprint ""
		(layer "B.Cu")
		(at 99.346766 -54.823106)
		(property "Reference" "C216"
			(at -1.556766 -1.271524 0)
			(unlocked yes)
			(layer "B.SilkS")
			(effects
				(font
					(size 0.7874 0.5842)
					(thickness 0.1524)
				)
				(justify mirror)
			)
		)
		(property "Value" "VAL*"
			(at 0 3.718306 0)
			(unlocked yes)
			(layer "B.Fab")
			(hide yes)
			(effects
				(font
					(size 0.7874 0.5842)
					(thickness 0.127)
				)
				(justify mirror)
			)
		)
		(property "Tolerance" "TOL*"
			(at 0 4.861306 0)
			(unlocked yes)
			(layer "Cmts.User")
			(hide yes)
			(effects
				(font
					(size 0.7874 0.5842)
					(thickness 0.127)
				)
				(justify mirror)
			)
		)
		(property "User Part Number" "PARTNUM*"
			(at 0 2.575306 0)
			(unlocked yes)
			(layer "Cmts.User")
			(hide yes)
			(effects
				(font
					(size 0.7874 0.5842)
					(thickness 0.127)
				)
				(justify mirror)
			)
		)
		(property "Device Type" "CAPACITOR-G105-0B104-CK,0.1UF,A"
			(at 0 1.432306 0)
			(unlocked yes)
			(layer "B.Fab")
			(hide yes)
			(effects
				(font
					(size 0.7874 0.5842)
					(thickness 0.127)
				)
				(justify mirror)
			)
		)
		(duplicate_pad_numbers_are_jumpers no)
		(fp_line
			(start -0.970026 -0.4699)
			(end -0.970026 0.4699)
			(stroke
				(width 0.1)
				(type default)
			)
			(layer "B.SilkS")
		)
		(fp_line
			(start -0.970026 0.4699)
			(end 0.970026 0.4699)
			(stroke
				(width 0.1)
				(type default)
			)
			(layer "B.SilkS")
		)
		(fp_line
			(start 0.970026 -0.4699)
			(end -0.970026 -0.4699)
			(stroke
				(width 0.1)
				(type default)
			)
			(layer "B.SilkS")
		)
		(fp_line
			(start 0.970026 0.4699)
			(end 0.970026 -0.4699)
			(stroke
				(width 0.1)
				(type default)
			)
			(layer "B.SilkS")
		)
		(fp_poly
			(pts
				(xy 0.970026 0.4699) (xy -0.970026 0.4699) (xy -0.970026 -0.4699) (xy 0.970026 -0.4699)
			)
			(stroke
				(width 0)
				(type default)
			)
			(fill no)
			(layer "B.CrtYd")
		)
		(fp_line
			(start -0.508 -0.3048)
			(end -0.508 0.3048)
			(stroke
				(width 0.1)
				(type default)
			)
			(layer "B.Fab")
		)
		(fp_line
			(start -0.508 0.3048)
			(end 0.508 0.3048)
			(stroke
				(width 0.1)
				(type default)
			)
			(layer "B.Fab")
		)
		(fp_line
			(start 0.508 -0.3048)
			(end -0.508 -0.3048)
			(stroke
				(width 0.1)
				(type default)
			)
			(layer "B.Fab")
		)
		(fp_line
			(start 0.508 0.3048)
			(end 0.508 -0.3048)
			(stroke
				(width 0.1)
				(type default)
			)
			(layer "B.Fab")
		)
		(pad "1" smd circle
			(at 0.500126 0 180)
			(size 0.635 0.635)
			(layers "B.Cu" "B.Mask" "B.Paste")
			(net "XP3R3V_FPGA")
		)
		(pad "2" smd circle
			(at -0.500126 0 180)
			(size 0.635 0.635)
			(layers "B.Cu" "B.Mask" "B.Paste")
			(net "SG")
		)
	)
	(footprint ""
		(layer "B.Cu")
		(at 117.347238 -49.823116 180)
		(property "Reference" "C130"
			(at 0.634238 1.834134 0)
			(unlocked yes)
			(layer "B.SilkS")
			(effects
				(font
					(size 0.635 0.4064)
					(thickness 0.1524)
				)
				(justify mirror)
			)
		)
		(property "Value" "VAL*"
			(at 0 3.718306 180)
			(unlocked yes)
			(layer "B.Fab")
			(hide yes)
			(effects
				(font
					(size 0.7874 0.5842)
					(thickness 0.127)
				)
				(justify mirror)
			)
		)
		(property "Device Type" "CAPACITOR-G105-0B104-CK,0.1UF,A"
			(at 0 1.432306 180)
			(unlocked yes)
			(layer "B.Fab")
			(hide yes)
			(effects
				(font
					(size 0.7874 0.5842)
					(thickness 0.127)
				)
				(justify mirror)
			)
		)
		(property "User Part Number" "PARTNUM*"
			(at 0 2.575306 180)
			(unlocked yes)
			(layer "Cmts.User")
			(hide yes)
			(effects
				(font
					(size 0.7874 0.5842)
					(thickness 0.127)
				)
				(justify mirror)
			)
		)
		(property "Tolerance" "TOL*"
			(at 0 4.861306 180)
			(unlocked yes)
			(layer "Cmts.User")
			(hide yes)
			(effects
				(font
					(size 0.7874 0.5842)
					(thickness 0.127)
				)
				(justify mirror)
			)
		)
		(duplicate_pad_numbers_are_jumpers no)
		(fp_line
			(start 0.970026 0.4699)
			(end 0.970026 -0.4699)
			(stroke
				(width 0.1)
				(type default)
			)
			(layer "B.SilkS")
		)
		(fp_line
			(start 0.970026 -0.4699)
			(end -0.970026 -0.4699)
			(stroke
				(width 0.1)
				(type default)
			)
			(layer "B.SilkS")
		)
		(fp_line
			(start -0.970026 0.4699)
			(end 0.970026 0.4699)
			(stroke
				(width 0.1)
				(type default)
			)
			(layer "B.SilkS")
		)
		(fp_line
			(start -0.970026 -0.4699)
			(end -0.970026 0.4699)
			(stroke
				(width 0.1)
				(type default)
			)
			(layer "B.SilkS")
		)
		(fp_poly
			(pts
				(xy 0.970026 0.4699) (xy -0.970026 0.4699) (xy -0.970026 -0.4699) (xy 0.970026 -0.4699)
			)
			(stroke
				(width 0)
				(type default)
			)
			(fill no)
			(layer "B.CrtYd")
		)
		(fp_line
			(start 0.508 0.3048)
			(end 0.508 -0.3048)
			(stroke
				(width 0.1)
				(type default)
			)
			(layer "B.Fab")
		)
		(fp_line
			(start 0.508 -0.3048)
			(end -0.508 -0.3048)
			(stroke
				(width 0.1)
				(type default)
			)
			(layer "B.Fab")
		)
		(fp_line
			(start -0.508 0.3048)
			(end 0.508 0.3048)
			(stroke
				(width 0.1)
				(type default)
			)
			(layer "B.Fab")
		)
		(fp_line
			(start -0.508 -0.3048)
			(end -0.508 0.3048)
			(stroke
				(width 0.1)
				(type default)
			)
			(layer "B.Fab")
		)
		(pad "1" smd circle
			(at 0.500126 0)
			(size 0.635 0.635)
			(layers "B.Cu" "B.Mask" "B.Paste")
			(net "XP3R3V_FPGA")
		)
		(pad "2" smd circle
			(at -0.500126 0)
			(size 0.635 0.635)
			(layers "B.Cu" "B.Mask" "B.Paste")
			(net "SG")
		)
	)
	(footprint ""
		(layer "B.Cu")
		(at 140.2842 -69.1134)
		(property "Reference" "R133"
			(at -5.0292 -0.57023 0)
			(unlocked yes)
			(layer "B.SilkS")
			(effects
				(font
					(size 0.7874 0.5842)
					(thickness 0.1524)
				)
				(justify mirror)
			)
		)
		(property "Value" "VAL*"
			(at -0.02032 2.13233 0)
			(unlocked yes)
			(layer "B.Fab")
			(hide yes)
			(effects
				(font
					(size 0.7874 0.5842)
					(thickness 0.1524)
				)
				(justify mirror)
			)
		)
		(property "Tolerance" "TOL*"
			(at -0.044704 3.05435 0)
			(unlocked yes)
			(layer "Cmts.User")
			(hide yes)
			(effects
				(font
					(size 0.7874 0.5842)
					(thickness 0.1524)
				)
				(justify mirror)
			)
		)
		(property "User Part Number" "PARTNUM*"
			(at -0.02032 4.024884 0)
			(unlocked yes)
			(layer "Cmts.User")
			(hide yes)
			(effects
				(font
					(size 0.7874 0.5842)
					(thickness 0.1524)
				)
				(justify mirror)
			)
		)
		(property "Device Type" "RESISTOR-G155-133R0-01,33OHM,1%"
			(at -0.008382 1.210564 0)
			(unlocked yes)
			(layer "B.Fab")
			(hide yes)
			(effects
				(font
					(size 0.7874 0.5842)
					(thickness 0.1524)
				)
				(justify mirror)
			)
		)
		(duplicate_pad_numbers_are_jumpers no)
		(fp_line
			(start -1.143 -0.5588)
			(end 1.143 -0.5588)
			(stroke
				(width 0.1)
				(type default)
			)
			(layer "B.SilkS")
		)
		(fp_line
			(start -1.143 0.5588)
			(end -1.143 -0.5588)
			(stroke
				(width 0.1)
				(type default)
			)
			(layer "B.SilkS")
		)
		(fp_line
			(start 1.143 -0.5588)
			(end 1.143 0.5588)
			(stroke
				(width 0.1)
				(type default)
			)
			(layer "B.SilkS")
		)
		(fp_line
			(start 1.143 0.5588)
			(end -1.143 0.5588)
			(stroke
				(width 0.1)
				(type default)
			)
			(layer "B.SilkS")
		)
		(fp_rect
			(start 1.143 0.5588)
			(end -1.143 -0.5588)
			(stroke
				(width 0)
				(type default)
			)
			(fill no)
			(layer "B.CrtYd")
		)
		(fp_line
			(start -0.508 -0.3048)
			(end 0.508 -0.3048)
			(stroke
				(width 0.1)
				(type default)
			)
			(layer "B.Fab")
		)
		(fp_line
			(start -0.508 0.3048)
			(end -0.508 -0.3048)
			(stroke
				(width 0.1)
				(type default)
			)
			(layer "B.Fab")
		)
		(fp_line
			(start 0.508 -0.3048)
			(end 0.508 0.3048)
			(stroke
				(width 0.1)
				(type default)
			)
			(layer "B.Fab")
		)
		(fp_line
			(start 0.508 0.3048)
			(end -0.508 0.3048)
			(stroke
				(width 0.1)
				(type default)
			)
			(layer "B.Fab")
		)
		(pad "1" smd rect
			(at 0.5334 0 180)
			(size 0.7112 0.6096)
			(layers "B.Cu" "B.Mask" "B.Paste")
			(net "XP3R3V_FPGA")
		)
		(pad "2" smd rect
			(at -0.5334 0 180)
			(size 0.7112 0.6096)
			(layers "B.Cu" "B.Mask" "B.Paste")
			(net "UNNAMED_127_G2001028301_I427_4")
		)
		(zone
			(layer "B.Cu")
			(hatch none 0.5)
			(connect_pads
				(clearance 0)
			)
			(min_thickness 0.25)
			(keepout
				(tracks allowed)
				(vias not_allowed)
				(pads allowed)
				(copperpour not_allowed)
				(footprints allowed)
			)
			(placement
				(enabled no)
				(sheetname "")
			)
			(fill
				(thermal_gap 0.5)
				(thermal_bridge_width 0.5)
				(island_removal_mode 0)
			)
			(polygon
				(pts
					(xy 140.3604 -68.8086) (xy 140.3604 -69.4182) (xy 140.208 -69.4182) (xy 140.208 -68.8086)
				)
			)
		)
	)
	(footprint ""
		(layer "B.Cu")
		(at 110.998 -27.94 90)
		(property "Reference" "R355"
			(at -2.667 -0.03937 270)
			(unlocked yes)
			(layer "B.SilkS")
			(effects
				(font
					(size 0.7874 0.5842)
					(thickness 0.1524)
				)
				(justify mirror)
			)
		)
		(property "Value" "VAL*"
			(at -0.02032 2.13233 90)
			(unlocked yes)
			(layer "B.Fab")
			(hide yes)
			(effects
				(font
					(size 0.7874 0.5842)
					(thickness 0.1524)
				)
				(justify mirror)
			)
		)
		(property "Tolerance" "TOL*"
			(at -0.044704 3.05435 90)
			(unlocked yes)
			(layer "Cmts.User")
			(hide yes)
			(effects
				(font
					(size 0.7874 0.5842)
					(thickness 0.1524)
				)
				(justify mirror)
			)
		)
		(property "User Part Number" "PARTNUM*"
			(at -0.02032 4.024884 90)
			(unlocked yes)
			(layer "Cmts.User")
			(hide yes)
			(effects
				(font
					(size 0.7874 0.5842)
					(thickness 0.1524)
				)
				(justify mirror)
			)
		)
		(property "Device Type" "RESISTOR-G155-11002-01,10KOHM,A"
			(at -0.008382 1.210564 90)
			(unlocked yes)
			(layer "B.Fab")
			(hide yes)
			(effects
				(font
					(size 0.7874 0.5842)
					(thickness 0.1524)
				)
				(justify mirror)
			)
		)
		(duplicate_pad_numbers_are_jumpers no)
		(fp_line
			(start 1.143 -0.5588)
			(end 1.143 0.5588)
			(stroke
				(width 0.1)
				(type default)
			)
			(layer "B.SilkS")
		)
		(fp_line
			(start -1.143 -0.5588)
			(end 1.143 -0.5588)
			(stroke
				(width 0.1)
				(type default)
			)
			(layer "B.SilkS")
		)
		(fp_line
			(start 1.143 0.5588)
			(end -1.143 0.5588)
			(stroke
				(width 0.1)
				(type default)
			)
			(layer "B.SilkS")
		)
		(fp_line
			(start -1.143 0.5588)
			(end -1.143 -0.5588)
			(stroke
				(width 0.1)
				(type default)
			)
			(layer "B.SilkS")
		)
		(fp_poly
			(pts
				(xy 1.143 0.5588) (xy -1.143 0.5588) (xy -1.143 -0.5588) (xy 1.143 -0.5588)
			)
			(stroke
				(width 0)
				(type default)
			)
			(fill no)
			(layer "B.CrtYd")
		)
		(fp_line
			(start 0.508 -0.3048)
			(end 0.508 0.3048)
			(stroke
				(width 0.1)
				(type default)
			)
			(layer "B.Fab")
		)
		(fp_line
			(start -0.508 -0.3048)
			(end 0.508 -0.3048)
			(stroke
				(width 0.1)
				(type default)
			)
			(layer "B.Fab")
		)
		(fp_line
			(start 0.508 0.3048)
			(end -0.508 0.3048)
			(stroke
				(width 0.1)
				(type default)
			)
			(layer "B.Fab")
		)
		(fp_line
			(start -0.508 0.3048)
			(end -0.508 -0.3048)
			(stroke
				(width 0.1)
				(type default)
			)
			(layer "B.Fab")
		)
		(pad "1" smd rect
			(at 0.5334 0 270)
			(size 0.7112 0.6096)
			(layers "B.Cu" "B.Mask" "B.Paste")
			(net "MHZ200CLKN_CLKIN")
		)
		(pad "2" smd rect
			(at -0.5334 0 270)
			(size 0.7112 0.6096)
			(layers "B.Cu" "B.Mask" "B.Paste")
			(net "XP2R5V_FPGA")
		)
		(zone
			(layer "B.Cu")
			(hatch none 0.5)
			(connect_pads
				(clearance 0)
			)
			(min_thickness 0.25)
			(keepout
				(tracks allowed)
				(vias not_allowed)
				(pads allowed)
				(copperpour not_allowed)
				(footprints allowed)
			)
			(placement
				(enabled no)
				(sheetname "")
			)
			(fill
				(thermal_gap 0.5)
				(thermal_bridge_width 0.5)
				(island_removal_mode 0)
			)
			(polygon
				(pts
					(xy 111.3028 -28.0162) (xy 110.6932 -28.0162) (xy 110.6932 -27.8638) (xy 111.3028 -27.8638)
				)
			)
		)
		(zone
			(layer "B.Cu")
			(hatch none 0.5)
			(connect_pads
				(clearance 0)
			)
			(min_thickness 0.25)
			(keepout
				(tracks not_allowed)
				(vias allowed)
				(pads allowed)
				(copperpour not_allowed)
				(footprints allowed)
			)
			(placement
				(enabled no)
				(sheetname "")
			)
			(fill
				(thermal_gap 0.5)
				(thermal_bridge_width 0.5)
				(island_removal_mode 0)
			)
			(polygon
				(pts
					(xy 111.3028 -28.0162) (xy 110.6932 -28.0162) (xy 110.6932 -27.8638) (xy 111.3028 -27.8638)
				)
			)
		)
	)
	(footprint ""
		(layer "B.Cu")
		(at 90.2716 -47.916846 180)
		(property "Reference" "R106"
			(at -0.762 2.500884 0)
			(unlocked yes)
			(layer "B.SilkS")
			(effects
				(font
					(size 0.7874 0.5842)
					(thickness 0.1524)
				)
				(justify mirror)
			)
		)
		(property "Value" "VAL*"
			(at -0.02032 2.13233 180)
			(unlocked yes)
			(layer "B.Fab")
			(hide yes)
			(effects
				(font
					(size 0.7874 0.5842)
					(thickness 0.1524)
				)
				(justify mirror)
			)
		)
		(property "Tolerance" "TOL*"
			(at -0.044704 3.05435 180)
			(unlocked yes)
			(layer "Cmts.User")
			(hide yes)
			(effects
				(font
					(size 0.7874 0.5842)
					(thickness 0.1524)
				)
				(justify mirror)
			)
		)
		(property "User Part Number" "PARTNUM*"
			(at -0.02032 4.024884 180)
			(unlocked yes)
			(layer "Cmts.User")
			(hide yes)
			(effects
				(font
					(size 0.7874 0.5842)
					(thickness 0.1524)
				)
				(justify mirror)
			)
		)
		(property "Device Type" "RESISTOR-G155-100R0-J0,0OHM,-"
			(at -0.008382 1.210564 180)
			(unlocked yes)
			(layer "B.Fab")
			(hide yes)
			(effects
				(font
					(size 0.7874 0.5842)
					(thickness 0.1524)
				)
				(justify mirror)
			)
		)
		(duplicate_pad_numbers_are_jumpers no)
		(fp_line
			(start 1.143 0.5588)
			(end -1.143 0.5588)
			(stroke
				(width 0.1)
				(type default)
			)
			(layer "B.SilkS")
		)
		(fp_line
			(start 1.143 -0.5588)
			(end 1.143 0.5588)
			(stroke
				(width 0.1)
				(type default)
			)
			(layer "B.SilkS")
		)
		(fp_line
			(start -1.143 0.5588)
			(end -1.143 -0.5588)
			(stroke
				(width 0.1)
				(type default)
			)
			(layer "B.SilkS")
		)
		(fp_line
			(start -1.143 -0.5588)
			(end 1.143 -0.5588)
			(stroke
				(width 0.1)
				(type default)
			)
			(layer "B.SilkS")
		)
		(fp_rect
			(start 1.143 -0.5588)
			(end -1.143 0.5588)
			(stroke
				(width 0)
				(type default)
			)
			(fill no)
			(layer "B.CrtYd")
		)
		(fp_line
			(start 0.508 0.3048)
			(end -0.508 0.3048)
			(stroke
				(width 0.1)
				(type default)
			)
			(layer "B.Fab")
		)
		(fp_line
			(start 0.508 -0.3048)
			(end 0.508 0.3048)
			(stroke
				(width 0.1)
				(type default)
			)
			(layer "B.Fab")
		)
		(fp_line
			(start -0.508 0.3048)
			(end -0.508 -0.3048)
			(stroke
				(width 0.1)
				(type default)
			)
			(layer "B.Fab")
		)
		(fp_line
			(start -0.508 -0.3048)
			(end 0.508 -0.3048)
			(stroke
				(width 0.1)
				(type default)
			)
			(layer "B.Fab")
		)
		(pad "1" smd rect
			(at 0.5334 0)
			(size 0.7112 0.6096)
			(layers "B.Cu" "B.Mask" "B.Paste")
			(net "MUX_USB_DP")
		)
		(pad "2" smd rect
			(at -0.5334 0)
			(size 0.7112 0.6096)
			(layers "B.Cu" "B.Mask" "B.Paste")
			(net "MAC_USB_DP")
		)
		(zone
			(layer "B.Cu")
			(hatch none 0.5)
			(connect_pads
				(clearance 0)
			)
			(min_thickness 0.25)
			(keepout
				(tracks allowed)
				(vias not_allowed)
				(pads allowed)
				(copperpour not_allowed)
				(footprints allowed)
			)
			(placement
				(enabled no)
				(sheetname "")
			)
			(fill
				(thermal_gap 0.5)
				(thermal_bridge_width 0.5)
				(island_removal_mode 0)
			)
			(polygon
				(pts
					(xy 90.1954 -47.612046) (xy 90.3478 -47.612046) (xy 90.3478 -48.221646) (xy 90.1954 -48.221646)
				)
			)
		)
	)
)
